(kicad_pcb
	(version 20260206)
	(generator "pcbnew")
	(generator_version "10.0")
	(general
		(thickness 1.6)
		(legacy_teardrops no)
	)
	(paper "A4")
	(title_block
		(title "04192023_DAF0TMB3IC0_F0TG_MB_C_brd_V02_OCP.brd")
		(comment 1 "Grand Teton / footprints 4275-4276 of 8354")
	)
	(layers
		(0 "F.Cu" signal "TOP")
		(4 "In1.Cu" signal "GND")
		(6 "In2.Cu" signal "IN1")
		(8 "In3.Cu" signal "GND1")
		(10 "In4.Cu" signal "IN2")
		(12 "In5.Cu" signal "GND2")
		(14 "In6.Cu" signal "IN3")
		(16 "In7.Cu" signal "GND3")
		(18 "In8.Cu" signal "VCC")
		(20 "In9.Cu" signal "VCC1")
		(22 "In10.Cu" signal "GND4")
		(24 "In11.Cu" signal "IN4")
		(26 "In12.Cu" signal "GND5")
		(28 "In13.Cu" signal "IN5")
		(30 "In14.Cu" signal "GND6")
		(32 "In15.Cu" signal "IN6")
		(34 "In16.Cu" signal "GND7")
		(2 "B.Cu" signal "BOTTOM")
		(9 "F.Adhes" user "F.Adhesive")
		(11 "B.Adhes" user "B.Adhesive")
		(13 "F.Paste" user "Package Geometry/Pastemask Top")
		(15 "B.Paste" user "Package Geometry/Pastemask Bottom")
		(5 "F.SilkS" user "Ref Des/Silkscreen Top")
		(7 "B.SilkS" user "Ref Des/Silkscreen Bottom")
		(1 "F.Mask" user "Board Geometry/Soldermask Top")
		(3 "B.Mask" user "Board Geometry/Soldermask Bottom")
		(17 "Dwgs.User" user "User.Drawings")
		(19 "Cmts.User" user "User.Comments")
		(21 "Eco1.User" user "User.Eco1")
		(23 "Eco2.User" user "User.Eco2")
		(25 "Edge.Cuts" user "Board Geometry/Outline")
		(27 "Margin" user)
		(31 "F.CrtYd" user "Package Geometry/Place Bound Top")
		(29 "B.CrtYd" user "Package Geometry/Place Bound Bottom")
		(35 "F.Fab" user "Ref Des/Assembly Top")
		(33 "B.Fab" user "Ref Des/Assembly Bottom")
	)
	(footprint ""
		(layer "F.Cu")
		(at 457.796646 -397.322802 -90)
		(property "Reference" "PC6577_2"
			(at 0 0 270)
			(layer "F.SilkS")
			(hide yes)
			(effects
				(font
					(size 1.27 1.27)
				)
			)
		)
		(property "Value" ""
			(at 0 0 270)
			(layer "F.Fab")
			(effects
				(font
					(size 1.27 1.27)
				)
			)
		)
		(duplicate_pad_numbers_are_jumpers no)
		(fp_line
			(start -0.7874 0.4064)
			(end -0.7874 -0.4064)
			(stroke
				(width 0.1524)
				(type default)
			)
			(layer "F.SilkS")
		)
		(fp_line
			(start 0.7874 0.4064)
			(end -0.7874 0.4064)
			(stroke
				(width 0.1524)
				(type default)
			)
			(layer "F.SilkS")
		)
		(fp_line
			(start -0.7874 -0.4064)
			(end 0.7874 -0.4064)
			(stroke
				(width 0.1524)
				(type default)
			)
			(layer "F.SilkS")
		)
		(fp_line
			(start 0.7874 -0.4064)
			(end 0.7874 0.4064)
			(stroke
				(width 0.1524)
				(type default)
			)
			(layer "F.SilkS")
		)
		(fp_line
			(start -0.67945 0.3048)
			(end -0.67945 -0.305054)
			(stroke
				(width 0.1)
				(type default)
			)
			(layer "F.Fab")
		)
		(fp_line
			(start -0.12065 0.3048)
			(end -0.67945 0.3048)
			(stroke
				(width 0.1)
				(type default)
			)
			(layer "F.Fab")
		)
		(fp_line
			(start 0.120396 0.3048)
			(end 0.120396 0.2794)
			(stroke
				(width 0.1)
				(type default)
			)
			(layer "F.Fab")
		)
		(fp_line
			(start 0.67945 0.3048)
			(end 0.120396 0.3048)
			(stroke
				(width 0.1)
				(type default)
			)
			(layer "F.Fab")
		)
		(fp_line
			(start -0.12065 0.2794)
			(end -0.12065 0.3048)
			(stroke
				(width 0.1)
				(type default)
			)
			(layer "F.Fab")
		)
		(fp_line
			(start 0.120396 0.2794)
			(end -0.12065 0.2794)
			(stroke
				(width 0.1)
				(type default)
			)
			(layer "F.Fab")
		)
		(fp_line
			(start -0.12065 -0.2794)
			(end 0.12065 -0.2794)
			(stroke
				(width 0.1)
				(type default)
			)
			(layer "F.Fab")
		)
		(fp_line
			(start 0.12065 -0.2794)
			(end 0.12065 -0.3048)
			(stroke
				(width 0.1)
				(type default)
			)
			(layer "F.Fab")
		)
		(fp_line
			(start 0.12065 -0.3048)
			(end 0.67945 -0.3048)
			(stroke
				(width 0.1)
				(type default)
			)
			(layer "F.Fab")
		)
		(fp_line
			(start 0.67945 -0.3048)
			(end 0.67945 0.3048)
			(stroke
				(width 0.1)
				(type default)
			)
			(layer "F.Fab")
		)
		(fp_line
			(start -0.67945 -0.305054)
			(end -0.12065 -0.305054)
			(stroke
				(width 0.1)
				(type default)
			)
			(layer "F.Fab")
		)
		(fp_line
			(start -0.12065 -0.305054)
			(end -0.12065 -0.2794)
			(stroke
				(width 0.1)
				(type default)
			)
			(layer "F.Fab")
		)
		(pad "1" smd circle
			(at -0.40005 0 270)
			(size 0 0)
			(layers "F.Cu" "F.Mask" "F.Paste")
			(net "SW_P12V_AUX_P0V9_RETIMER_CPU0_FLT")
		)
		(pad "2" smd circle
			(at 0.40005 0 270)
			(size 0 0)
			(layers "F.Cu" "F.Mask" "F.Paste")
			(net "GND")
		)
	)
	(footprint ""
		(layer "F.Cu")
		(at 250.317 -39.064946 -90)
		(property "Reference" "R3972"
			(at 0 0 270)
			(layer "F.SilkS")
			(hide yes)
			(effects
				(font
					(size 1.27 1.27)
				)
			)
		)
		(property "Value" ""
			(at 0 0 270)
			(layer "F.Fab")
			(effects
				(font
					(size 1.27 1.27)
				)
			)
		)
		(duplicate_pad_numbers_are_jumpers no)
		(fp_line
			(start -0.7874 0.4064)
			(end -0.7874 -0.4064)
			(stroke
				(width 0.1524)
				(type default)
			)
			(layer "F.SilkS")
		)
		(fp_line
			(start 0.7874 0.4064)
			(end -0.7874 0.4064)
			(stroke
				(width 0.1524)
				(type default)
			)
			(layer "F.SilkS")
		)
		(fp_line
			(start -0.7874 -0.4064)
			(end 0.7874 -0.4064)
			(stroke
				(width 0.1524)
				(type default)
			)
			(layer "F.SilkS")
		)
		(fp_line
			(start 0.7874 -0.4064)
			(end 0.7874 0.4064)
			(stroke
				(width 0.1524)
				(type default)
			)
			(layer "F.SilkS")
		)
		(fp_line
			(start -0.67945 0.3048)
			(end -0.67945 -0.305054)
			(stroke
				(width 0.1)
				(type default)
			)
			(layer "F.Fab")
		)
		(fp_line
			(start -0.12065 0.3048)
			(end -0.67945 0.3048)
			(stroke
				(width 0.1)
				(type default)
			)
			(layer "F.Fab")
		)
		(fp_line
			(start 0.120396 0.3048)
			(end 0.120396 0.2794)
			(stroke
				(width 0.1)
				(type default)
			)
			(layer "F.Fab")
		)
		(fp_line
			(start 0.67945 0.3048)
			(end 0.120396 0.3048)
			(stroke
				(width 0.1)
				(type default)
			)
			(layer "F.Fab")
		)
		(fp_line
			(start -0.12065 0.2794)
			(end -0.12065 0.3048)
			(stroke
				(width 0.1)
				(type default)
			)
			(layer "F.Fab")
		)
		(fp_line
			(start 0.120396 0.2794)
			(end -0.12065 0.2794)
			(stroke
				(width 0.1)
				(type default)
			)
			(layer "F.Fab")
		)
		(fp_line
			(start -0.12065 -0.2794)
			(end 0.12065 -0.2794)
			(stroke
				(width 0.1)
				(type default)
			)
			(layer "F.Fab")
		)
		(fp_line
			(start 0.12065 -0.2794)
			(end 0.12065 -0.3048)
			(stroke
				(width 0.1)
				(type default)
			)
			(layer "F.Fab")
		)
		(fp_line
			(start 0.12065 -0.3048)
			(end 0.67945 -0.3048)
			(stroke
				(width 0.1)
				(type default)
			)
			(layer "F.Fab")
		)
		(fp_line
			(start 0.67945 -0.3048)
			(end 0.67945 0.3048)
			(stroke
				(width 0.1)
				(type default)
			)
			(layer "F.Fab")
		)
		(fp_line
			(start -0.67945 -0.305054)
			(end -0.12065 -0.305054)
			(stroke
				(width 0.1)
				(type default)
			)
			(layer "F.Fab")
		)
		(fp_line
			(start -0.12065 -0.305054)
			(end -0.12065 -0.2794)
			(stroke
				(width 0.1)
				(type default)
			)
			(layer "F.Fab")
		)
		(pad "1" smd circle
			(at -0.40005 0 270)
			(size 0 0)
			(layers "F.Cu" "F.Mask" "F.Paste")
			(net "P12V_E1S_PWRGD_0")
		)
		(pad "2" smd circle
			(at 0.40005 0 270)
			(size 0 0)
			(layers "F.Cu" "F.Mask" "F.Paste")
			(net "HP_LVC3_E1S_0_HSC_PWRGD")
		)
	)
)
